(kicad_pcb
	(version 20260206)
	(generator "pcbnew")
	(generator_version "10.0")
	(general
		(thickness 1.6)
		(legacy_teardrops no)
	)
	(paper "A4")
	(title_block
		(title "01162023_DA0F0TEBIF0_F0T_Expander_BD_F_brd_V02_OCP.brd")
		(comment 1 "Grand Teton / footprints 4388-4393 of 9728")
	)
	(layers
		(0 "F.Cu" signal "TOP")
		(4 "In1.Cu" signal "GND")
		(6 "In2.Cu" signal "VCC")
		(8 "In3.Cu" signal "VCC1")
		(10 "In4.Cu" signal "GND1")
		(12 "In5.Cu" signal "IN1")
		(14 "In6.Cu" signal "GND2")
		(16 "In7.Cu" signal "IN2")
		(18 "In8.Cu" signal "GND3")
		(20 "In9.Cu" signal "IN3")
		(22 "In10.Cu" signal "GND4")
		(24 "In11.Cu" signal "IN4")
		(26 "In12.Cu" signal "GND5")
		(28 "In13.Cu" signal "IN5")
		(30 "In14.Cu" signal "GND6")
		(32 "In15.Cu" signal "IN6")
		(34 "In16.Cu" signal "GND7")
		(2 "B.Cu" signal "BOTTOM")
		(9 "F.Adhes" user "F.Adhesive")
		(11 "B.Adhes" user "B.Adhesive")
		(13 "F.Paste" user "Package Geometry/Pastemask Top")
		(15 "B.Paste" user "Package Geometry/Pastemask Bottom")
		(5 "F.SilkS" user "Ref Des/Silkscreen Top")
		(7 "B.SilkS" user "Ref Des/Silkscreen Bottom")
		(1 "F.Mask" user "Board Geometry/Soldermask Top")
		(3 "B.Mask" user "Board Geometry/Soldermask Bottom")
		(17 "Dwgs.User" user "User.Drawings")
		(19 "Cmts.User" user "User.Comments")
		(21 "Eco1.User" user "User.Eco1")
		(23 "Eco2.User" user "User.Eco2")
		(25 "Edge.Cuts" user "Board Geometry/Outline")
		(27 "Margin" user)
		(31 "F.CrtYd" user "Package Geometry/Place Bound Top")
		(29 "B.CrtYd" user "Package Geometry/Place Bound Bottom")
		(35 "F.Fab" user "Ref Des/Assembly Top")
		(33 "B.Fab" user "Ref Des/Assembly Bottom")
	)
	(footprint ""
		(layer "F.Cu")
		(at 257.764026 -237.213648 -90)
		(property "Reference" "C4424"
			(at 0 0 270)
			(layer "F.SilkS")
			(hide yes)
			(effects
				(font
					(size 1.27 1.27)
				)
			)
		)
		(property "Value" ""
			(at 0 0 270)
			(layer "F.Fab")
			(effects
				(font
					(size 1.27 1.27)
				)
			)
		)
		(duplicate_pad_numbers_are_jumpers no)
		(fp_line
			(start -0.7874 0.4064)
			(end -0.7874 -0.4064)
			(stroke
				(width 0.1524)
				(type default)
			)
			(layer "F.SilkS")
		)
		(fp_line
			(start 0.7874 0.4064)
			(end -0.7874 0.4064)
			(stroke
				(width 0.1524)
				(type default)
			)
			(layer "F.SilkS")
		)
		(fp_line
			(start -0.7874 -0.4064)
			(end 0.7874 -0.4064)
			(stroke
				(width 0.1524)
				(type default)
			)
			(layer "F.SilkS")
		)
		(fp_line
			(start 0.7874 -0.4064)
			(end 0.7874 0.4064)
			(stroke
				(width 0.1524)
				(type default)
			)
			(layer "F.SilkS")
		)
		(fp_line
			(start -0.67945 0.3048)
			(end -0.67945 -0.305054)
			(stroke
				(width 0.1)
				(type default)
			)
			(layer "F.Fab")
		)
		(fp_line
			(start -0.12065 0.3048)
			(end -0.67945 0.3048)
			(stroke
				(width 0.1)
				(type default)
			)
			(layer "F.Fab")
		)
		(fp_line
			(start 0.120396 0.3048)
			(end 0.120396 0.2794)
			(stroke
				(width 0.1)
				(type default)
			)
			(layer "F.Fab")
		)
		(fp_line
			(start 0.67945 0.3048)
			(end 0.120396 0.3048)
			(stroke
				(width 0.1)
				(type default)
			)
			(layer "F.Fab")
		)
		(fp_line
			(start -0.12065 0.2794)
			(end -0.12065 0.3048)
			(stroke
				(width 0.1)
				(type default)
			)
			(layer "F.Fab")
		)
		(fp_line
			(start 0.120396 0.2794)
			(end -0.12065 0.2794)
			(stroke
				(width 0.1)
				(type default)
			)
			(layer "F.Fab")
		)
		(fp_line
			(start -0.12065 -0.2794)
			(end 0.12065 -0.2794)
			(stroke
				(width 0.1)
				(type default)
			)
			(layer "F.Fab")
		)
		(fp_line
			(start 0.12065 -0.2794)
			(end 0.12065 -0.3048)
			(stroke
				(width 0.1)
				(type default)
			)
			(layer "F.Fab")
		)
		(fp_line
			(start 0.12065 -0.3048)
			(end 0.67945 -0.3048)
			(stroke
				(width 0.1)
				(type default)
			)
			(layer "F.Fab")
		)
		(fp_line
			(start 0.67945 -0.3048)
			(end 0.67945 0.3048)
			(stroke
				(width 0.1)
				(type default)
			)
			(layer "F.Fab")
		)
		(fp_line
			(start -0.67945 -0.305054)
			(end -0.12065 -0.305054)
			(stroke
				(width 0.1)
				(type default)
			)
			(layer "F.Fab")
		)
		(fp_line
			(start -0.12065 -0.305054)
			(end -0.12065 -0.2794)
			(stroke
				(width 0.1)
				(type default)
			)
			(layer "F.Fab")
		)
		(pad "1" smd circle
			(at -0.40005 0 270)
			(size 0 0)
			(layers "F.Cu" "F.Mask" "F.Paste")
			(net "P5V_AUX")
		)
		(pad "2" smd circle
			(at 0.40005 0 270)
			(size 0 0)
			(layers "F.Cu" "F.Mask" "F.Paste")
			(net "GND")
		)
	)
	(footprint ""
		(layer "F.Cu")
		(at 384.834384 -250.070874 -90)
		(property "Reference" "R1411"
			(at 0 0 270)
			(layer "F.SilkS")
			(hide yes)
			(effects
				(font
					(size 1.27 1.27)
				)
			)
		)
		(property "Value" ""
			(at 0 0 270)
			(layer "F.Fab")
			(effects
				(font
					(size 1.27 1.27)
				)
			)
		)
		(duplicate_pad_numbers_are_jumpers no)
		(fp_line
			(start -0.7874 0.4064)
			(end -0.7874 -0.4064)
			(stroke
				(width 0.1524)
				(type default)
			)
			(layer "F.SilkS")
		)
		(fp_line
			(start 0.7874 0.4064)
			(end -0.7874 0.4064)
			(stroke
				(width 0.1524)
				(type default)
			)
			(layer "F.SilkS")
		)
		(fp_line
			(start -0.7874 -0.4064)
			(end 0.7874 -0.4064)
			(stroke
				(width 0.1524)
				(type default)
			)
			(layer "F.SilkS")
		)
		(fp_line
			(start 0.7874 -0.4064)
			(end 0.7874 0.4064)
			(stroke
				(width 0.1524)
				(type default)
			)
			(layer "F.SilkS")
		)
		(fp_line
			(start -0.67945 0.3048)
			(end -0.67945 -0.305054)
			(stroke
				(width 0.1)
				(type default)
			)
			(layer "F.Fab")
		)
		(fp_line
			(start -0.12065 0.3048)
			(end -0.67945 0.3048)
			(stroke
				(width 0.1)
				(type default)
			)
			(layer "F.Fab")
		)
		(fp_line
			(start 0.120396 0.3048)
			(end 0.120396 0.2794)
			(stroke
				(width 0.1)
				(type default)
			)
			(layer "F.Fab")
		)
		(fp_line
			(start 0.67945 0.3048)
			(end 0.120396 0.3048)
			(stroke
				(width 0.1)
				(type default)
			)
			(layer "F.Fab")
		)
		(fp_line
			(start -0.12065 0.2794)
			(end -0.12065 0.3048)
			(stroke
				(width 0.1)
				(type default)
			)
			(layer "F.Fab")
		)
		(fp_line
			(start 0.120396 0.2794)
			(end -0.12065 0.2794)
			(stroke
				(width 0.1)
				(type default)
			)
			(layer "F.Fab")
		)
		(fp_line
			(start -0.12065 -0.2794)
			(end 0.12065 -0.2794)
			(stroke
				(width 0.1)
				(type default)
			)
			(layer "F.Fab")
		)
		(fp_line
			(start 0.12065 -0.2794)
			(end 0.12065 -0.3048)
			(stroke
				(width 0.1)
				(type default)
			)
			(layer "F.Fab")
		)
		(fp_line
			(start 0.12065 -0.3048)
			(end 0.67945 -0.3048)
			(stroke
				(width 0.1)
				(type default)
			)
			(layer "F.Fab")
		)
		(fp_line
			(start 0.67945 -0.3048)
			(end 0.67945 0.3048)
			(stroke
				(width 0.1)
				(type default)
			)
			(layer "F.Fab")
		)
		(fp_line
			(start -0.67945 -0.305054)
			(end -0.12065 -0.305054)
			(stroke
				(width 0.1)
				(type default)
			)
			(layer "F.Fab")
		)
		(fp_line
			(start -0.12065 -0.305054)
			(end -0.12065 -0.2794)
			(stroke
				(width 0.1)
				(type default)
			)
			(layer "F.Fab")
		)
		(pad "1" smd circle
			(at -0.40005 0 270)
			(size 0 0)
			(layers "F.Cu" "F.Mask" "F.Paste")
			(net "PEX3_MODE_SEL6")
		)
		(pad "2" smd circle
			(at 0.40005 0 270)
			(size 0 0)
			(layers "F.Cu" "F.Mask" "F.Paste")
			(net "P1V8_PEX")
		)
	)
	(footprint ""
		(layer "F.Cu")
		(at 139.768072 -19.453098)
		(property "Reference" "R1667"
			(at 0 0 0)
			(layer "F.SilkS")
			(hide yes)
			(effects
				(font
					(size 1.27 1.27)
				)
			)
		)
		(property "Value" ""
			(at 0 0 0)
			(layer "F.Fab")
			(effects
				(font
					(size 1.27 1.27)
				)
			)
		)
		(duplicate_pad_numbers_are_jumpers no)
		(fp_line
			(start -0.7874 -0.4064)
			(end 0.7874 -0.4064)
			(stroke
				(width 0.1524)
				(type default)
			)
			(layer "F.SilkS")
		)
		(fp_line
			(start -0.7874 0.4064)
			(end -0.7874 -0.4064)
			(stroke
				(width 0.1524)
				(type default)
			)
			(layer "F.SilkS")
		)
		(fp_line
			(start 0.7874 -0.4064)
			(end 0.7874 0.4064)
			(stroke
				(width 0.1524)
				(type default)
			)
			(layer "F.SilkS")
		)
		(fp_line
			(start 0.7874 0.4064)
			(end -0.7874 0.4064)
			(stroke
				(width 0.1524)
				(type default)
			)
			(layer "F.SilkS")
		)
		(fp_line
			(start -0.67945 -0.305054)
			(end -0.12065 -0.305054)
			(stroke
				(width 0.1)
				(type default)
			)
			(layer "F.Fab")
		)
		(fp_line
			(start -0.67945 0.3048)
			(end -0.67945 -0.305054)
			(stroke
				(width 0.1)
				(type default)
			)
			(layer "F.Fab")
		)
		(fp_line
			(start -0.12065 -0.305054)
			(end -0.12065 -0.2794)
			(stroke
				(width 0.1)
				(type default)
			)
			(layer "F.Fab")
		)
		(fp_line
			(start -0.12065 -0.2794)
			(end 0.12065 -0.2794)
			(stroke
				(width 0.1)
				(type default)
			)
			(layer "F.Fab")
		)
		(fp_line
			(start -0.12065 0.2794)
			(end -0.12065 0.3048)
			(stroke
				(width 0.1)
				(type default)
			)
			(layer "F.Fab")
		)
		(fp_line
			(start -0.12065 0.3048)
			(end -0.67945 0.3048)
			(stroke
				(width 0.1)
				(type default)
			)
			(layer "F.Fab")
		)
		(fp_line
			(start 0.120396 0.2794)
			(end -0.12065 0.2794)
			(stroke
				(width 0.1)
				(type default)
			)
			(layer "F.Fab")
		)
		(fp_line
			(start 0.120396 0.3048)
			(end 0.120396 0.2794)
			(stroke
				(width 0.1)
				(type default)
			)
			(layer "F.Fab")
		)
		(fp_line
			(start 0.12065 -0.3048)
			(end 0.67945 -0.3048)
			(stroke
				(width 0.1)
				(type default)
			)
			(layer "F.Fab")
		)
		(fp_line
			(start 0.12065 -0.2794)
			(end 0.12065 -0.3048)
			(stroke
				(width 0.1)
				(type default)
			)
			(layer "F.Fab")
		)
		(fp_line
			(start 0.67945 -0.3048)
			(end 0.67945 0.3048)
			(stroke
				(width 0.1)
				(type default)
			)
			(layer "F.Fab")
		)
		(fp_line
			(start 0.67945 0.3048)
			(end 0.120396 0.3048)
			(stroke
				(width 0.1)
				(type default)
			)
			(layer "F.Fab")
		)
		(pad "1" smd circle
			(at -0.40005 0)
			(size 0 0)
			(layers "F.Cu" "F.Mask" "F.Paste")
			(net "SMB_ISO_SSD4_R_SDA")
		)
		(pad "2" smd circle
			(at 0.40005 0)
			(size 0 0)
			(layers "F.Cu" "F.Mask" "F.Paste")
			(net "SMB_ISO_SSD4_SDA")
		)
	)
	(footprint ""
		(layer "F.Cu")
		(at 212.046566 -235.756958 90)
		(property "Reference" "R1539"
			(at 0 0 90)
			(layer "F.SilkS")
			(hide yes)
			(effects
				(font
					(size 1.27 1.27)
				)
			)
		)
		(property "Value" ""
			(at 0 0 90)
			(layer "F.Fab")
			(effects
				(font
					(size 1.27 1.27)
				)
			)
		)
		(duplicate_pad_numbers_are_jumpers no)
		(fp_line
			(start 0.7874 -0.4064)
			(end 0.7874 0.4064)
			(stroke
				(width 0.1524)
				(type default)
			)
			(layer "F.SilkS")
		)
		(fp_line
			(start -0.7874 -0.4064)
			(end 0.7874 -0.4064)
			(stroke
				(width 0.1524)
				(type default)
			)
			(layer "F.SilkS")
		)
		(fp_line
			(start 0.7874 0.4064)
			(end -0.7874 0.4064)
			(stroke
				(width 0.1524)
				(type default)
			)
			(layer "F.SilkS")
		)
		(fp_line
			(start -0.7874 0.4064)
			(end -0.7874 -0.4064)
			(stroke
				(width 0.1524)
				(type default)
			)
			(layer "F.SilkS")
		)
		(fp_line
			(start -0.12065 -0.305054)
			(end -0.12065 -0.2794)
			(stroke
				(width 0.1)
				(type default)
			)
			(layer "F.Fab")
		)
		(fp_line
			(start -0.67945 -0.305054)
			(end -0.12065 -0.305054)
			(stroke
				(width 0.1)
				(type default)
			)
			(layer "F.Fab")
		)
		(fp_line
			(start 0.67945 -0.3048)
			(end 0.67945 0.3048)
			(stroke
				(width 0.1)
				(type default)
			)
			(layer "F.Fab")
		)
		(fp_line
			(start 0.12065 -0.3048)
			(end 0.67945 -0.3048)
			(stroke
				(width 0.1)
				(type default)
			)
			(layer "F.Fab")
		)
		(fp_line
			(start 0.12065 -0.2794)
			(end 0.12065 -0.3048)
			(stroke
				(width 0.1)
				(type default)
			)
			(layer "F.Fab")
		)
		(fp_line
			(start -0.12065 -0.2794)
			(end 0.12065 -0.2794)
			(stroke
				(width 0.1)
				(type default)
			)
			(layer "F.Fab")
		)
		(fp_line
			(start 0.120396 0.2794)
			(end -0.12065 0.2794)
			(stroke
				(width 0.1)
				(type default)
			)
			(layer "F.Fab")
		)
		(fp_line
			(start -0.12065 0.2794)
			(end -0.12065 0.3048)
			(stroke
				(width 0.1)
				(type default)
			)
			(layer "F.Fab")
		)
		(fp_line
			(start 0.67945 0.3048)
			(end 0.120396 0.3048)
			(stroke
				(width 0.1)
				(type default)
			)
			(layer "F.Fab")
		)
		(fp_line
			(start 0.120396 0.3048)
			(end 0.120396 0.2794)
			(stroke
				(width 0.1)
				(type default)
			)
			(layer "F.Fab")
		)
		(fp_line
			(start -0.12065 0.3048)
			(end -0.67945 0.3048)
			(stroke
				(width 0.1)
				(type default)
			)
			(layer "F.Fab")
		)
		(fp_line
			(start -0.67945 0.3048)
			(end -0.67945 -0.305054)
			(stroke
				(width 0.1)
				(type default)
			)
			(layer "F.Fab")
		)
		(pad "1" smd circle
			(at -0.40005 0 90)
			(size 0 0)
			(layers "F.Cu" "F.Mask" "F.Paste")
			(net "P1V8_PEX")
		)
		(pad "2" smd circle
			(at 0.40005 0 90)
			(size 0 0)
			(layers "F.Cu" "F.Mask" "F.Paste")
			(net "SMB_PEX_LS_SCL")
		)
	)
	(footprint ""
		(layer "F.Cu")
		(at 421.247316 -20.35556)
		(property "Reference" "C3974"
			(at 0 0 0)
			(layer "F.SilkS")
			(hide yes)
			(effects
				(font
					(size 1.27 1.27)
				)
			)
		)
		(property "Value" ""
			(at 0 0 0)
			(layer "F.Fab")
			(effects
				(font
					(size 1.27 1.27)
				)
			)
		)
		(duplicate_pad_numbers_are_jumpers no)
		(fp_line
			(start -0.7874 -0.4064)
			(end 0.7874 -0.4064)
			(stroke
				(width 0.1524)
				(type default)
			)
			(layer "F.SilkS")
		)
		(fp_line
			(start -0.7874 0.4064)
			(end -0.7874 -0.4064)
			(stroke
				(width 0.1524)
				(type default)
			)
			(layer "F.SilkS")
		)
		(fp_line
			(start 0.7874 -0.4064)
			(end 0.7874 0.4064)
			(stroke
				(width 0.1524)
				(type default)
			)
			(layer "F.SilkS")
		)
		(fp_line
			(start 0.7874 0.4064)
			(end -0.7874 0.4064)
			(stroke
				(width 0.1524)
				(type default)
			)
			(layer "F.SilkS")
		)
		(fp_line
			(start -0.67945 -0.305054)
			(end -0.12065 -0.305054)
			(stroke
				(width 0.1)
				(type default)
			)
			(layer "F.Fab")
		)
		(fp_line
			(start -0.67945 0.3048)
			(end -0.67945 -0.305054)
			(stroke
				(width 0.1)
				(type default)
			)
			(layer "F.Fab")
		)
		(fp_line
			(start -0.12065 -0.305054)
			(end -0.12065 -0.2794)
			(stroke
				(width 0.1)
				(type default)
			)
			(layer "F.Fab")
		)
		(fp_line
			(start -0.12065 -0.2794)
			(end 0.12065 -0.2794)
			(stroke
				(width 0.1)
				(type default)
			)
			(layer "F.Fab")
		)
		(fp_line
			(start -0.12065 0.2794)
			(end -0.12065 0.3048)
			(stroke
				(width 0.1)
				(type default)
			)
			(layer "F.Fab")
		)
		(fp_line
			(start -0.12065 0.3048)
			(end -0.67945 0.3048)
			(stroke
				(width 0.1)
				(type default)
			)
			(layer "F.Fab")
		)
		(fp_line
			(start 0.120396 0.2794)
			(end -0.12065 0.2794)
			(stroke
				(width 0.1)
				(type default)
			)
			(layer "F.Fab")
		)
		(fp_line
			(start 0.120396 0.3048)
			(end 0.120396 0.2794)
			(stroke
				(width 0.1)
				(type default)
			)
			(layer "F.Fab")
		)
		(fp_line
			(start 0.12065 -0.3048)
			(end 0.67945 -0.3048)
			(stroke
				(width 0.1)
				(type default)
			)
			(layer "F.Fab")
		)
		(fp_line
			(start 0.12065 -0.2794)
			(end 0.12065 -0.3048)
			(stroke
				(width 0.1)
				(type default)
			)
			(layer "F.Fab")
		)
		(fp_line
			(start 0.67945 -0.3048)
			(end 0.67945 0.3048)
			(stroke
				(width 0.1)
				(type default)
			)
			(layer "F.Fab")
		)
		(fp_line
			(start 0.67945 0.3048)
			(end 0.120396 0.3048)
			(stroke
				(width 0.1)
				(type default)
			)
			(layer "F.Fab")
		)
		(pad "1" smd circle
			(at -0.40005 0)
			(size 0 0)
			(layers "F.Cu" "F.Mask" "F.Paste")
			(net "P12V_SSD14")
		)
		(pad "2" smd circle
			(at 0.40005 0)
			(size 0 0)
			(layers "F.Cu" "F.Mask" "F.Paste")
			(net "GND")
		)
	)
	(footprint ""
		(layer "F.Cu")
		(at 260.6548 -22.961346 90)
		(property "Reference" "R1687"
			(at 0 0 90)
			(layer "F.SilkS")
			(hide yes)
			(effects
				(font
					(size 1.27 1.27)
				)
			)
		)
		(property "Value" ""
			(at 0 0 90)
			(layer "F.Fab")
			(effects
				(font
					(size 1.27 1.27)
				)
			)
		)
		(duplicate_pad_numbers_are_jumpers no)
		(fp_line
			(start 0.7874 -0.4064)
			(end 0.7874 0.4064)
			(stroke
				(width 0.1524)
				(type default)
			)
			(layer "F.SilkS")
		)
		(fp_line
			(start -0.7874 -0.4064)
			(end 0.7874 -0.4064)
			(stroke
				(width 0.1524)
				(type default)
			)
			(layer "F.SilkS")
		)
		(fp_line
			(start 0.7874 0.4064)
			(end -0.7874 0.4064)
			(stroke
				(width 0.1524)
				(type default)
			)
			(layer "F.SilkS")
		)
		(fp_line
			(start -0.7874 0.4064)
			(end -0.7874 -0.4064)
			(stroke
				(width 0.1524)
				(type default)
			)
			(layer "F.SilkS")
		)
		(fp_line
			(start -0.12065 -0.305054)
			(end -0.12065 -0.2794)
			(stroke
				(width 0.1)
				(type default)
			)
			(layer "F.Fab")
		)
		(fp_line
			(start -0.67945 -0.305054)
			(end -0.12065 -0.305054)
			(stroke
				(width 0.1)
				(type default)
			)
			(layer "F.Fab")
		)
		(fp_line
			(start 0.67945 -0.3048)
			(end 0.67945 0.3048)
			(stroke
				(width 0.1)
				(type default)
			)
			(layer "F.Fab")
		)
		(fp_line
			(start 0.12065 -0.3048)
			(end 0.67945 -0.3048)
			(stroke
				(width 0.1)
				(type default)
			)
			(layer "F.Fab")
		)
		(fp_line
			(start 0.12065 -0.2794)
			(end 0.12065 -0.3048)
			(stroke
				(width 0.1)
				(type default)
			)
			(layer "F.Fab")
		)
		(fp_line
			(start -0.12065 -0.2794)
			(end 0.12065 -0.2794)
			(stroke
				(width 0.1)
				(type default)
			)
			(layer "F.Fab")
		)
		(fp_line
			(start 0.120396 0.2794)
			(end -0.12065 0.2794)
			(stroke
				(width 0.1)
				(type default)
			)
			(layer "F.Fab")
		)
		(fp_line
			(start -0.12065 0.2794)
			(end -0.12065 0.3048)
			(stroke
				(width 0.1)
				(type default)
			)
			(layer "F.Fab")
		)
		(fp_line
			(start 0.67945 0.3048)
			(end 0.120396 0.3048)
			(stroke
				(width 0.1)
				(type default)
			)
			(layer "F.Fab")
		)
		(fp_line
			(start 0.120396 0.3048)
			(end 0.120396 0.2794)
			(stroke
				(width 0.1)
				(type default)
			)
			(layer "F.Fab")
		)
		(fp_line
			(start -0.12065 0.3048)
			(end -0.67945 0.3048)
			(stroke
				(width 0.1)
				(type default)
			)
			(layer "F.Fab")
		)
		(fp_line
			(start -0.67945 0.3048)
			(end -0.67945 -0.305054)
			(stroke
				(width 0.1)
				(type default)
			)
			(layer "F.Fab")
		)
		(pad "1" smd circle
			(at -0.40005 0 90)
			(size 0 0)
			(layers "F.Cu" "F.Mask" "F.Paste")
			(net "SMB_SSD8_ISO_EN")
		)
		(pad "2" smd circle
			(at 0.40005 0 90)
			(size 0 0)
			(layers "F.Cu" "F.Mask" "F.Paste")
			(net "P3V3_AUX")
		)
	)
)
